(kicad_pcb
	(version 20241229)
	(generator "pcbnew")
	(generator_version "9.0")
	(general
		(thickness 1.711)
		(legacy_teardrops no)
	)
	(paper "A4")
	(title_block
		(title "Antmicro Baseboard for Jetson AGX Thor")
		(date "2026-02-18")
		(rev "1.1.0")
		(company "Antmicro Ltd")
		(comment 1 "www.antmicro.com")
		(comment 9 "footprints 462-466 of 1170")
	)
	(layers
		(0 "F.Cu" signal)
		(4 "In1.Cu" signal)
		(6 "In2.Cu" signal)
		(8 "In3.Cu" signal)
		(10 "In4.Cu" jumper)
		(12 "In5.Cu" signal)
		(14 "In6.Cu" signal)
		(16 "In7.Cu" signal)
		(18 "In8.Cu" signal)
		(2 "B.Cu" signal)
		(9 "F.Adhes" user "F.Adhesive")
		(11 "B.Adhes" user "B.Adhesive")
		(13 "F.Paste" user)
		(15 "B.Paste" user)
		(5 "F.SilkS" user "F.Silkscreen")
		(7 "B.SilkS" user "B.Silkscreen")
		(1 "F.Mask" user)
		(3 "B.Mask" user)
		(17 "Dwgs.User" user "User.Drawings")
		(19 "Cmts.User" user "User.Comments")
		(21 "Eco1.User" user "User.Eco1")
		(23 "Eco2.User" user "User.Eco2")
		(25 "Edge.Cuts" user)
		(27 "Margin" user)
		(31 "F.CrtYd" user "F.Courtyard")
		(29 "B.CrtYd" user "B.Courtyard")
		(35 "F.Fab" user)
		(33 "B.Fab" user)
	)
	(footprint "antmicro-footprints:C_0805_2012Metric"
		(layer "F.Cu")
		(at 176.345 126.92 90)
		(descr "Capacitor SMD 0805")
		(tags "capacitor SMD 0805")
		(property "Reference" "C46"
			(at 1.52 -6.685 90)
			(layer "F.SilkS")
			(effects
				(font
					(size 0.7 0.7)
					(thickness 0.15)
				)
				(justify left bottom)
			)
		)
		(property "Value" "C_22u_25V_0805"
			(at -2.055717 1.963152 90)
			(layer "F.Fab")
			(effects
				(font
					(size 0.7 0.7)
					(thickness 0.15)
				)
				(justify left bottom)
			)
		)
		(property "Datasheet" "https://product.samsungsem.com/mlcc/CL21A226MAYNNN.do"
			(at 0 0 90)
			(layer "F.Fab")
			(hide yes)
			(effects
				(font
					(size 1.27 1.27)
					(thickness 0.15)
				)
			)
		)
		(property "Description" "SMT Multilayer Ceramic Capacitor, 22uF, +/-20%, 25V, X5R, 0805 [2012 Metric]"
			(at 0 0 90)
			(layer "F.Fab")
			(hide yes)
			(effects
				(font
					(size 1.27 1.27)
					(thickness 0.15)
				)
			)
		)
		(property "MPN" "CL21A226MAYNNNE"
			(at 0 0 90)
			(unlocked yes)
			(layer "F.Fab")
			(hide yes)
			(effects
				(font
					(size 1 1)
					(thickness 0.15)
				)
			)
		)
		(property "Manufacturer" "Samsung Electro-Mechanics"
			(at 0 0 90)
			(unlocked yes)
			(layer "F.Fab")
			(hide yes)
			(effects
				(font
					(size 1 1)
					(thickness 0.15)
				)
			)
		)
		(property "License" "Apache-2.0"
			(at 0 0 90)
			(unlocked yes)
			(layer "F.Fab")
			(hide yes)
			(effects
				(font
					(size 1 1)
					(thickness 0.15)
				)
			)
		)
		(property "Author" "Antmicro"
			(at 0 0 90)
			(unlocked yes)
			(layer "F.Fab")
			(hide yes)
			(effects
				(font
					(size 1 1)
					(thickness 0.15)
				)
			)
		)
		(property "Val" "22u"
			(at 0 0 90)
			(unlocked yes)
			(layer "F.Fab")
			(hide yes)
			(effects
				(font
					(size 1 1)
					(thickness 0.15)
				)
			)
		)
		(property "Voltage" "25V"
			(at 0 0 90)
			(unlocked yes)
			(layer "F.Fab")
			(hide yes)
			(effects
				(font
					(size 1 1)
					(thickness 0.15)
				)
			)
		)
		(property "Dielectric" "X5R"
			(at 0 0 90)
			(unlocked yes)
			(layer "F.Fab")
			(hide yes)
			(effects
				(font
					(size 1 1)
					(thickness 0.15)
				)
			)
		)
		(property "Public" "False"
			(at 0 0 90)
			(unlocked yes)
			(layer "F.Fab")
			(hide yes)
			(effects
				(font
					(size 1 1)
					(thickness 0.15)
				)
			)
		)
		(sheetname "/DCDC/")
		(sheetfile "dcdc.kicad_sch")
		(attr smd)
		(fp_line
			(start -0.3 -0.7)
			(end 0.3 -0.7)
			(stroke
				(width 0.15)
				(type solid)
			)
			(layer "F.SilkS")
		)
		(fp_line
			(start -0.3 0.7)
			(end 0.3 0.7)
			(stroke
				(width 0.15)
				(type solid)
			)
			(layer "F.SilkS")
		)
		(fp_rect
			(start 1.95 -0.9)
			(end -1.95 0.9)
			(stroke
				(width 0.05)
				(type default)
			)
			(fill no)
			(layer "F.CrtYd")
		)
		(fp_rect
			(start -0.95 -0.675)
			(end 0.95 0.675)
			(stroke
				(width 0.15)
				(type solid)
			)
			(fill no)
			(layer "F.Fab")
		)
		(fp_text user "Author: Antmicro"
			(at -1.9 5.947 90)
			(layer "F.Fab")
			(effects
				(font
					(size 0.7 0.7)
					(thickness 0.15)
				)
				(justify left bottom)
			)
		)
		(fp_text user "${REFERENCE}"
			(at -1.9 3.947 90)
			(layer "F.Fab")
			(effects
				(font
					(size 0.7 0.7)
					(thickness 0.15)
				)
				(justify left bottom)
			)
		)
		(fp_text user "License: Apache-2.0"
			(at -1.9 4.947 90)
			(layer "F.Fab")
			(effects
				(font
					(size 0.7 0.7)
					(thickness 0.15)
				)
				(justify left bottom)
			)
		)
		(pad "1" smd roundrect
			(at -1.1 0 90)
			(size 1.2 1.3)
			(layers "F.Cu" "F.Mask" "F.Paste")
			(roundrect_rratio 0.25)
			(net 1 "GND")
			(pintype "passive")
		)
		(pad "2" smd roundrect
			(at 1.1 0 90)
			(size 1.2 1.3)
			(layers "F.Cu" "F.Mask" "F.Paste")
			(roundrect_rratio 0.25)
			(net 13 "VCC")
			(pintype "passive")
		)
	)
	(footprint "antmicro-footprints:C_0603_1608Metric_EIA"
		(layer "F.Cu")
		(at 176.27 130.18 -90)
		(descr "Capacitor SMD 0603, IPC-7351 Density Level A")
		(tags "Capacitor 0603")
		(property "Reference" "C64"
			(at -4.28 9.77 90)
			(layer "F.SilkS")
			(effects
				(font
					(size 0.7 0.7)
					(thickness 0.15)
				)
				(justify right top)
			)
		)
		(property "Value" "C_22u_16V_0603"
			(at -1.42757 1.770288 90)
			(layer "F.Fab")
			(effects
				(font
					(size 0.7 0.7)
					(thickness 0.15)
				)
				(justify right top)
			)
		)
		(property "Datasheet" "https://product.samsungsem.com/mlcc/CL10A226MO7JZN.do"
			(at 0 0 90)
			(layer "F.Fab")
			(hide yes)
			(effects
				(font
					(size 1.27 1.27)
					(thickness 0.15)
				)
			)
		)
		(property "Description" "SMD Multilayer Ceramic Capacitor"
			(at 0 0 90)
			(layer "F.Fab")
			(hide yes)
			(effects
				(font
					(size 1.27 1.27)
					(thickness 0.15)
				)
			)
		)
		(property "Manufacturer" "Samsung Electro-Mechanics"
			(at 0 0 270)
			(unlocked yes)
			(layer "F.Fab")
			(hide yes)
			(effects
				(font
					(size 1 1)
					(thickness 0.15)
				)
			)
		)
		(property "MPN" "CL10A226MO7JZNC"
			(at 0 0 270)
			(unlocked yes)
			(layer "F.Fab")
			(hide yes)
			(effects
				(font
					(size 1 1)
					(thickness 0.15)
				)
			)
		)
		(property "Val" "22u"
			(at 0 0 270)
			(unlocked yes)
			(layer "F.Fab")
			(hide yes)
			(effects
				(font
					(size 1 1)
					(thickness 0.15)
				)
			)
		)
		(property "License" "Apache-2.0"
			(at 0 0 270)
			(unlocked yes)
			(layer "F.Fab")
			(hide yes)
			(effects
				(font
					(size 1 1)
					(thickness 0.15)
				)
			)
		)
		(property "Author" "Antmicro"
			(at 0 0 270)
			(unlocked yes)
			(layer "F.Fab")
			(hide yes)
			(effects
				(font
					(size 1 1)
					(thickness 0.15)
				)
			)
		)
		(property "Voltage" "16V"
			(at 0 0 270)
			(unlocked yes)
			(layer "F.Fab")
			(hide yes)
			(effects
				(font
					(size 1 1)
					(thickness 0.15)
				)
			)
		)
		(property "Dielectric" ""
			(at 0 0 270)
			(unlocked yes)
			(layer "F.Fab")
			(hide yes)
			(effects
				(font
					(size 1 1)
					(thickness 0.15)
				)
			)
		)
		(sheetname "/DCDC/")
		(sheetfile "dcdc.kicad_sch")
		(attr smd)
		(fp_line
			(start -0.15 0.55)
			(end 0.15 0.55)
			(stroke
				(width 0.15)
				(type solid)
			)
			(layer "F.SilkS")
		)
		(fp_line
			(start -0.15 -0.55)
			(end 0.15 -0.55)
			(stroke
				(width 0.15)
				(type solid)
			)
			(layer "F.SilkS")
		)
		(fp_rect
			(start -1.25 -0.65)
			(end 1.25 0.65)
			(stroke
				(width 0.05)
				(type solid)
			)
			(fill no)
			(layer "F.CrtYd")
		)
		(fp_rect
			(start -0.8 -0.45)
			(end 0.8 0.45)
			(stroke
				(width 0.15)
				(type solid)
			)
			(fill no)
			(layer "F.Fab")
		)
		(fp_text user "${REFERENCE}"
			(at -1.682 3.895 90)
			(layer "F.Fab")
			(effects
				(font
					(size 0.7 0.7)
					(thickness 0.15)
				)
				(justify right top)
			)
		)
		(fp_text user "Author: Antmicro"
			(at -1.682 4.894 90)
			(layer "F.Fab")
			(effects
				(font
					(size 0.7 0.7)
					(thickness 0.15)
				)
				(justify right top)
			)
		)
		(fp_text user "License: Apache-2.0"
			(at -1.682 5.895 90)
			(layer "F.Fab")
			(effects
				(font
					(size 0.7 0.7)
					(thickness 0.15)
				)
				(justify right top)
			)
		)
		(pad "1" smd roundrect
			(at -0.7 0 270)
			(size 0.8 1.1)
			(layers "F.Cu" "F.Mask" "F.Paste")
			(roundrect_rratio 0.2)
			(net 1 "GND")
			(pintype "passive")
		)
		(pad "2" smd roundrect
			(at 0.7 0 270)
			(size 0.8 1.1)
			(layers "F.Cu" "F.Mask" "F.Paste")
			(roundrect_rratio 0.2)
			(net 567 "/DCDC/3V3_OUT")
			(pintype "passive")
		)
	)
	(footprint "antmicro-footprints:R_0402_1005Metric"
		(layer "F.Cu")
		(at 128.81 143.2 -90)
		(descr "Resistor SMD 0402")
		(tags "resistor SMD 0402")
		(property "Reference" "R340"
			(at 1 0.41 90)
			(layer "F.SilkS")
			(effects
				(font
					(size 0.7 0.7)
					(thickness 0.15)
				)
				(justify right top)
			)
		)
		(property "Value" "R_10k_0402"
			(at -1.011843 1.772046 90)
			(layer "F.Fab")
			(effects
				(font
					(size 0.7 0.7)
					(thickness 0.15)
				)
				(justify right top)
			)
		)
		(property "Datasheet" "https://www.bourns.com/docs/product-datasheets/cr.pdf"
			(at 0 0 90)
			(layer "F.Fab")
			(hide yes)
			(effects
				(font
					(size 1.27 1.27)
					(thickness 0.15)
				)
			)
		)
		(property "Description" "SMD Chip Resistor, 10 kohm, ± 1%, 62.5 mW, 0402 [1005 Metric], Thick Film, General Purpose"
			(at 0 0 90)
			(layer "F.Fab")
			(hide yes)
			(effects
				(font
					(size 1.27 1.27)
					(thickness 0.15)
				)
			)
		)
		(property "MPN" "CR0402-FX-1002GLF"
			(at 0 0 270)
			(unlocked yes)
			(layer "F.Fab")
			(hide yes)
			(effects
				(font
					(size 1 1)
					(thickness 0.15)
				)
			)
		)
		(property "Manufacturer" "Bourns"
			(at 0 0 270)
			(unlocked yes)
			(layer "F.Fab")
			(hide yes)
			(effects
				(font
					(size 1 1)
					(thickness 0.15)
				)
			)
		)
		(property "License" "Apache-2.0"
			(at 0 0 270)
			(unlocked yes)
			(layer "F.Fab")
			(hide yes)
			(effects
				(font
					(size 1 1)
					(thickness 0.15)
				)
			)
		)
		(property "Author" "Antmicro"
			(at 0 0 270)
			(unlocked yes)
			(layer "F.Fab")
			(hide yes)
			(effects
				(font
					(size 1 1)
					(thickness 0.15)
				)
			)
		)
		(property "Val" "10k"
			(at 0 0 270)
			(unlocked yes)
			(layer "F.Fab")
			(hide yes)
			(effects
				(font
					(size 1 1)
					(thickness 0.15)
				)
			)
		)
		(property "Tolerance" "1%"
			(at 0 0 270)
			(unlocked yes)
			(layer "F.Fab")
			(hide yes)
			(effects
				(font
					(size 1 1)
					(thickness 0.15)
				)
			)
		)
		(sheetname "/Expansion connector/")
		(sheetfile "expansion_connector.kicad_sch")
		(attr smd exclude_from_pos_files exclude_from_bom dnp)
		(fp_poly
			(pts
				(xy -0.925 -0.47) (xy 0.925 -0.47) (xy 0.925 0.47) (xy -0.925 0.47)
			)
			(stroke
				(width 0.05)
				(type default)
			)
			(fill no)
			(layer "F.CrtYd")
		)
		(fp_poly
			(pts
				(xy -0.5 -0.25) (xy 0.5 -0.25) (xy 0.5 0.25) (xy -0.5 0.25)
			)
			(stroke
				(width 0.15)
				(type solid)
			)
			(fill no)
			(layer "F.Fab")
		)
		(fp_text user "License: Apache-2.0"
			(at -0.949999 5.169 90)
			(layer "F.Fab")
			(effects
				(font
					(size 0.7 0.7)
					(thickness 0.15)
				)
				(justify right top)
			)
		)
		(fp_text user "${REFERENCE}"
			(at -0.95 3.168 90)
			(layer "F.Fab")
			(effects
				(font
					(size 0.7 0.7)
					(thickness 0.15)
				)
				(justify right top)
			)
		)
		(fp_text user "Author: Antmicro"
			(at -0.95 4.169 90)
			(layer "F.Fab")
			(effects
				(font
					(size 0.7 0.7)
					(thickness 0.15)
				)
				(justify right top)
			)
		)
		(pad "1" smd roundrect
			(at -0.48 0 270)
			(size 0.59 0.64)
			(layers "F.Cu" "F.Mask" "F.Paste")
			(roundrect_rratio 0.25)
			(net 677 "/Expansion connector/ADDR0")
			(pintype "passive")
		)
		(pad "2" smd roundrect
			(at 0.48 0 270)
			(size 0.59 0.64)
			(layers "F.Cu" "F.Mask" "F.Paste")
			(roundrect_rratio 0.25)
			(net 1 "GND")
			(pintype "passive")
		)
	)
	(footprint "antmicro-footprints:R_0603_1608Metric"
		(layer "F.Cu")
		(at 169.859468 149.049468 180)
		(descr "Resistor SMD 0603")
		(tags "resistor SMD 0603")
		(property "Reference" "R22"
			(at 1.3 0.295 0)
			(layer "F.SilkS")
			(effects
				(font
					(size 0.7 0.7)
					(thickness 0.15)
				)
				(justify right top)
			)
		)
		(property "Value" "R_0R_22.4A_0603"
			(at 0 1.6 0)
			(layer "F.Fab")
			(effects
				(font
					(size 0.7 0.7)
					(thickness 0.15)
				)
				(justify right top)
			)
		)
		(property "Datasheet" "https://fscdn.rohm.com/en/products/databook/datasheet/passive/resistor/chip_resistor/pmr-jpw-e.pdf"
			(at 0 0 0)
			(layer "F.Fab")
			(hide yes)
			(effects
				(font
					(size 1.27 1.27)
					(thickness 0.15)
				)
			)
		)
		(property "Description" "SMD Chip Resistor"
			(at 0 0 0)
			(layer "F.Fab")
			(hide yes)
			(effects
				(font
					(size 1.27 1.27)
					(thickness 0.15)
				)
			)
		)
		(property "Manufacturer" "ROHM Semiconductor"
			(at 0 0 0)
			(unlocked yes)
			(layer "F.Fab")
			(hide yes)
			(effects
				(font
					(size 1 1)
					(thickness 0.15)
				)
			)
		)
		(property "MPN" "PMR03EZPJ000"
			(at 0 0 0)
			(unlocked yes)
			(layer "F.Fab")
			(hide yes)
			(effects
				(font
					(size 1 1)
					(thickness 0.15)
				)
			)
		)
		(property "Val" "0R"
			(at 0 0 0)
			(unlocked yes)
			(layer "F.Fab")
			(hide yes)
			(effects
				(font
					(size 1 1)
					(thickness 0.15)
				)
			)
		)
		(property "Author" "Antmicro"
			(at 0 0 0)
			(unlocked yes)
			(layer "F.Fab")
			(hide yes)
			(effects
				(font
					(size 1 1)
					(thickness 0.15)
				)
			)
		)
		(property "License" "Apache-2.0"
			(at 0 0 0)
			(unlocked yes)
			(layer "F.Fab")
			(hide yes)
			(effects
				(font
					(size 1 1)
					(thickness 0.15)
				)
			)
		)
		(property "Max. Curr." "22.4A"
			(at 0 0 0)
			(unlocked yes)
			(layer "F.Fab")
			(hide yes)
			(effects
				(font
					(size 1 1)
					(thickness 0.15)
				)
			)
		)
		(property "Tolerance" "template_tolerance"
			(at 0 0 0)
			(unlocked yes)
			(layer "F.Fab")
			(hide yes)
			(effects
				(font
					(size 1 1)
					(thickness 0.15)
				)
			)
		)
		(sheetname "/DCDC/")
		(sheetfile "dcdc.kicad_sch")
		(attr smd)
		(fp_line
			(start -0.15 0.4)
			(end 0.15 0.4)
			(stroke
				(width 0.15)
				(type solid)
			)
			(layer "F.SilkS")
		)
		(fp_line
			(start -0.15 -0.4)
			(end 0.15 -0.4)
			(stroke
				(width 0.15)
				(type solid)
			)
			(layer "F.SilkS")
		)
		(fp_rect
			(start -1.25 -0.65)
			(end 1.25 0.65)
			(stroke
				(width 0.05)
				(type solid)
			)
			(fill no)
			(layer "F.CrtYd")
		)
		(fp_rect
			(start -0.8 -0.4)
			(end 0.8 0.4)
			(stroke
				(width 0.15)
				(type solid)
			)
			(fill no)
			(layer "F.Fab")
		)
		(fp_text user "Author: Antmicro"
			(at -1.25 4.9 0)
			(layer "F.Fab")
			(effects
				(font
					(size 0.7 0.7)
					(thickness 0.15)
				)
				(justify right top)
			)
		)
		(fp_text user "${REFERENCE}"
			(at -1.25 3.898 0)
			(layer "F.Fab")
			(effects
				(font
					(size 0.7 0.7)
					(thickness 0.15)
				)
				(justify right top)
			)
		)
		(fp_text user "License: Apache-2.0"
			(at -1.25 5.9 0)
			(layer "F.Fab")
			(effects
				(font
					(size 0.7 0.7)
					(thickness 0.15)
				)
				(justify right top)
			)
		)
		(pad "1" smd roundrect
			(at -0.7 0 180)
			(size 0.8 1)
			(layers "F.Cu" "F.Mask" "F.Paste")
			(roundrect_rratio 0.2)
			(net 880 "/DCDC/12V_OUT")
			(pintype "passive")
		)
		(pad "2" smd roundrect
			(at 0.7 0 180)
			(size 0.8 1)
			(layers "F.Cu" "F.Mask" "F.Paste")
			(roundrect_rratio 0.2)
			(net 634 "+12V")
			(pintype "passive")
		)
	)
	(footprint "antmicro-footprints:C_0402_1005Metric"
		(layer "F.Cu")
		(at 61.6 61.2)
		(descr "Capacitor SMD 0402")
		(tags "capacitor SMD 0402")
		(property "Reference" "C155"
			(at -1.4 -0.8 0)
			(layer "F.SilkS")
			(effects
				(font
					(size 0.7 0.7)
					(thickness 0.15)
				)
				(justify left bottom)
			)
		)
		(property "Value" "C_100n_0402"
			(at -1.022927 2.155213 0)
			(layer "F.Fab")
			(effects
				(font
					(size 0.7 0.7)
					(thickness 0.15)
				)
				(justify left bottom)
			)
		)
		(property "Datasheet" "https://www.murata.com/products/productdetail?partno=GRM155R61H104KE14%23"
			(at 0 0 0)
			(layer "F.Fab")
			(hide yes)
			(effects
				(font
					(size 1.27 1.27)
					(thickness 0.15)
				)
			)
		)
		(property "Description" "SMD Multilayer Ceramic Capacitor, 0.1 µF, 50 V, 0402 [1005 Metric], ± 10%, X5R, GRM Series"
			(at 0 0 0)
			(layer "F.Fab")
			(hide yes)
			(effects
				(font
					(size 1.27 1.27)
					(thickness 0.15)
				)
			)
		)
		(property "Manufacturer" "Murata"
			(at 0 0 0)
			(unlocked yes)
			(layer "F.Fab")
			(hide yes)
			(effects
				(font
					(size 1 1)
					(thickness 0.15)
				)
			)
		)
		(property "MPN" "GRM155R61H104KE14D"
			(at 0 0 0)
			(unlocked yes)
			(layer "F.Fab")
			(hide yes)
			(effects
				(font
					(size 1 1)
					(thickness 0.15)
				)
			)
		)
		(property "Val" "100n"
			(at 0 0 0)
			(unlocked yes)
			(layer "F.Fab")
			(hide yes)
			(effects
				(font
					(size 1 1)
					(thickness 0.15)
				)
			)
		)
		(property "License" "Apache-2.0"
			(at 0 0 0)
			(unlocked yes)
			(layer "F.Fab")
			(hide yes)
			(effects
				(font
					(size 1 1)
					(thickness 0.15)
				)
			)
		)
		(property "Author" "Antmicro"
			(at 0 0 0)
			(unlocked yes)
			(layer "F.Fab")
			(hide yes)
			(effects
				(font
					(size 1 1)
					(thickness 0.15)
				)
			)
		)
		(property "Voltage" "50V"
			(at 0 0 0)
			(unlocked yes)
			(layer "F.Fab")
			(hide yes)
			(effects
				(font
					(size 1 1)
					(thickness 0.15)
				)
			)
		)
		(property "Dielectric" "X5R"
			(at 0 0 0)
			(unlocked yes)
			(layer "F.Fab")
			(hide yes)
			(effects
				(font
					(size 1 1)
					(thickness 0.15)
				)
			)
		)
		(sheetname "/CSI/")
		(sheetfile "csi.kicad_sch")
		(attr smd)
		(fp_poly
			(pts
				(xy -0.925 -0.47) (xy -0.925 0.47) (xy 0.925 0.47) (xy 0.925 -0.47)
			)
			(stroke
				(width 0.05)
				(type default)
			)
			(fill no)
			(layer "F.CrtYd")
		)
		(fp_line
			(start -0.494 -0.25)
			(end 0.504 -0.25)
			(stroke
				(width 0.15)
				(type solid)
			)
			(layer "F.Fab")
		)
		(fp_line
			(start -0.494 0.248)
			(end -0.494 -0.25)
			(stroke
				(width 0.15)
				(type solid)
			)
			(layer "F.Fab")
		)
		(fp_line
			(start 0.504 -0.25)
			(end 0.504 0.248)
			(stroke
				(width 0.15)
				(type solid)
			)
			(layer "F.Fab")
		)
		(fp_line
			(start 0.504 0.248)
			(end -0.494 0.248)
			(stroke
				(width 0.15)
				(type solid)
			)
			(layer "F.Fab")
		)
		(fp_text user "${REFERENCE}"
			(at -0.939 4.599 0)
			(layer "F.Fab")
			(effects
				(font
					(size 0.7 0.7)
					(thickness 0.15)
				)
				(justify left bottom)
			)
		)
		(fp_text user "Author: Antmicro"
			(at -0.939 3.399 0)
			(layer "F.Fab")
			(effects
				(font
					(size 0.7 0.7)
					(thickness 0.15)
				)
				(justify left bottom)
			)
		)
		(fp_text user "License: Apache-2.0"
			(at -0.939 5.799 0)
			(layer "F.Fab")
			(effects
				(font
					(size 0.7 0.7)
					(thickness 0.15)
				)
				(justify left bottom)
			)
		)
		(pad "1" smd roundrect
			(at -0.48 0)
			(size 0.59 0.64)
			(layers "F.Cu" "F.Mask" "F.Paste")
			(roundrect_rratio 0.25)
			(net 1 "GND")
			(pintype "passive")
		)
		(pad "2" smd roundrect
			(at 0.48 0)
			(size 0.59 0.64)
			(layers "F.Cu" "F.Mask" "F.Paste")
			(roundrect_rratio 0.25)
			(net 11 "+1V8")
			(pintype "passive")
		)
	)
)
